# BASEBOARD_FAB2 (Tioga Pass) — schematic netlist excerpt (pin names and nets, part order shuffled) for the footprints in the layout excerpt that follows; sources: Cadence DE-HDL packaged netlist, KiCad conversion of Wiwynn_Tioga_Pass_MB.brd

C3U9  CAP  10UF 16V 10% X6S  pkg 0805  page 216 : A = VR_FET_SW_P12V_STBY_PVDDQ_ABC ; B = GND
C7T2  CAP  10UF 4V 20% X6S  pkg 0603LF  page 233 : A = PVPP_GHJ ; B = GND
R6P11  RES  42.2 1.0% EMPTY  pkg 0402  page 103 : A = CLK_100M_CPU0_PE_REFCLK_DP ; B = GND

(kicad_pcb
	(version 20260206)
	(generator "pcbnew")
	(generator_version "10.0")
	(general
		(thickness 1.6)
		(legacy_teardrops no)
	)
	(paper "A4")
	(title_block
		(title "Wiwynn_Tioga_Pass_MB.brd")
		(comment 1 "Tioga Pass / footprints 3471-3473 of 4770")
	)
	(layers
		(0 "F.Cu" signal "TOP")
		(4 "In1.Cu" signal "L2GND")
		(6 "In2.Cu" signal "L3")
		(8 "In3.Cu" signal "L4GND")
		(10 "In4.Cu" signal "L5")
		(12 "In5.Cu" signal "L6GND")
		(14 "In6.Cu" signal "L7VCC")
		(16 "In7.Cu" signal "L8VCC")
		(18 "In8.Cu" signal "L9GND")
		(20 "In9.Cu" signal "L10")
		(22 "In10.Cu" signal "L11GND")
		(24 "In11.Cu" signal "L12")
		(26 "In12.Cu" signal "L13GND")
		(2 "B.Cu" signal "BOTTOM")
		(9 "F.Adhes" user "F.Adhesive")
		(11 "B.Adhes" user "B.Adhesive")
		(13 "F.Paste" user "Package Geometry/Pastemask Top")
		(15 "B.Paste" user "Package Geometry/Pastemask Bottom")
		(5 "F.SilkS" user "Ref Des/Silkscreen Top")
		(7 "B.SilkS" user "Ref Des/Silkscreen Bottom")
		(1 "F.Mask" user "Board Geometry/Soldermask Top")
		(3 "B.Mask" user "Board Geometry/Soldermask Bottom")
		(17 "Dwgs.User" user "User.Drawings")
		(19 "Cmts.User" user "User.Comments")
		(21 "Eco1.User" user "User.Eco1")
		(23 "Eco2.User" user "User.Eco2")
		(25 "Edge.Cuts" user "Board Geometry/Outline")
		(27 "Margin" user)
		(31 "F.CrtYd" user "Package Geometry/Place Bound Top")
		(29 "B.CrtYd" user "Package Geometry/Place Bound Bottom")
		(35 "F.Fab" user "Ref Des/Assembly Top")
		(33 "B.Fab" user "Ref Des/Assembly Bottom")
	)
	(footprint ""
		(layer "B.Cu")
		(at 155.194 -17.78 90)
		(property "Reference" "C7T2"
			(at 0 0 90)
			(layer "B.SilkS")
			(hide yes)
			(effects
				(font
					(size 1.27 1.27)
				)
				(justify mirror)
			)
		)
		(property "Value" ""
			(at 0 0 90)
			(layer "B.Fab")
			(effects
				(font
					(size 1.27 1.27)
				)
				(justify mirror)
			)
		)
		(duplicate_pad_numbers_are_jumpers no)
		(fp_poly
			(pts
				(xy 0.4953 -0.2032) (xy -0.4953 -0.2032) (xy -0.4953 1.6002) (xy 0.4953 1.6002)
			)
			(stroke
				(width 0)
				(type default)
			)
			(fill no)
			(layer "B.CrtYd")
		)
		(fp_line
			(start 0.4953 -0.2032)
			(end -0.4953 -0.2032)
			(stroke
				(width 0.1)
				(type default)
			)
			(layer "B.Fab")
		)
		(fp_line
			(start -0.4953 -0.2032)
			(end -0.4953 1.6002)
			(stroke
				(width 0.1)
				(type default)
			)
			(layer "B.Fab")
		)
		(fp_line
			(start 0.4953 1.6002)
			(end 0.4953 -0.2032)
			(stroke
				(width 0.1)
				(type default)
			)
			(layer "B.Fab")
		)
		(fp_line
			(start -0.4953 1.6002)
			(end 0.4953 1.6002)
			(stroke
				(width 0.1)
				(type default)
			)
			(layer "B.Fab")
		)
		(pad "1" smd rect
			(at 0 0 270)
			(size 0.762 0.889)
			(layers "B.Cu" "B.Mask" "B.Paste")
			(net "PVPP_GHJ")
		)
		(pad "2" smd rect
			(at 0 1.397 270)
			(size 0.762 0.889)
			(layers "B.Cu" "B.Mask" "B.Paste")
			(net "GND")
		)
		(zone
			(layer "B.Cu")
			(hatch none 0.5)
			(connect_pads
				(clearance 0)
			)
			(min_thickness 0.25)
			(keepout
				(tracks not_allowed)
				(vias allowed)
				(pads allowed)
				(copperpour not_allowed)
				(footprints allowed)
			)
			(placement
				(enabled no)
				(sheetname "")
			)
			(fill
				(thermal_gap 0.5)
				(thermal_bridge_width 0.5)
				(island_removal_mode 0)
			)
			(polygon
				(pts
					(xy 155.6385 -18.161) (xy 155.6385 -17.399) (xy 156.1465 -17.399) (xy 156.1465 -18.161)
				)
			)
		)
	)
	(footprint ""
		(layer "B.Cu")
		(at 347.469206 4.370578 -90)
		(property "Reference" "C3U9"
			(at 0 0 90)
			(layer "B.SilkS")
			(hide yes)
			(effects
				(font
					(size 1.27 1.27)
				)
				(justify mirror)
			)
		)
		(property "Value" ""
			(at 0 0 90)
			(layer "B.Fab")
			(effects
				(font
					(size 1.27 1.27)
				)
				(justify mirror)
			)
		)
		(duplicate_pad_numbers_are_jumpers no)
		(fp_rect
			(start 0.7239 1.9939)
			(end -0.7239 -0.2159)
			(stroke
				(width 0)
				(type default)
			)
			(fill no)
			(layer "B.CrtYd")
		)
		(fp_line
			(start -0.7239 1.9939)
			(end -0.7239 -0.2159)
			(stroke
				(width 0.1)
				(type default)
			)
			(layer "B.Fab")
		)
		(fp_line
			(start 0.7239 1.9939)
			(end -0.7239 1.9939)
			(stroke
				(width 0.1)
				(type default)
			)
			(layer "B.Fab")
		)
		(fp_line
			(start -0.7239 -0.2159)
			(end 0.7239 -0.2159)
			(stroke
				(width 0.1)
				(type default)
			)
			(layer "B.Fab")
		)
		(fp_line
			(start 0.7239 -0.2159)
			(end 0.7239 1.9939)
			(stroke
				(width 0.1)
				(type default)
			)
			(layer "B.Fab")
		)
		(pad "1" smd rect
			(at 0 0 90)
			(size 1.27 1.016)
			(layers "B.Cu" "B.Mask" "B.Paste")
			(net "VR_FET_SW_P12V_STBY_PVDDQ_ABC")
		)
		(pad "2" smd rect
			(at 0 1.778 90)
			(size 1.27 1.016)
			(layers "B.Cu" "B.Mask" "B.Paste")
			(net "GND")
		)
		(zone
			(layer "B.Cu")
			(hatch none 0.5)
			(connect_pads
				(clearance 0)
			)
			(min_thickness 0.25)
			(keepout
				(tracks not_allowed)
				(vias allowed)
				(pads allowed)
				(copperpour not_allowed)
				(footprints allowed)
			)
			(placement
				(enabled no)
				(sheetname "")
			)
			(fill
				(thermal_gap 0.5)
				(thermal_bridge_width 0.5)
				(island_removal_mode 0)
			)
			(polygon
				(pts
					(xy 346.199206 5.005578) (xy 346.961206 5.005578) (xy 346.961206 3.735578) (xy 346.199206 3.735578)
				)
			)
		)
	)
	(footprint ""
		(layer "B.Cu")
		(at 176.212754 -83.947 -90)
		(property "Reference" "R6P11"
			(at 0 0 90)
			(layer "B.SilkS")
			(hide yes)
			(effects
				(font
					(size 1.27 1.27)
				)
				(justify mirror)
			)
		)
		(property "Value" ""
			(at 0 0 90)
			(layer "B.Fab")
			(effects
				(font
					(size 1.27 1.27)
				)
				(justify mirror)
			)
		)
		(duplicate_pad_numbers_are_jumpers no)
		(fp_poly
			(pts
				(xy 0.2794 -0.1016) (xy -0.2794 -0.1016) (xy -0.2794 0.9906) (xy 0.2794 0.9906)
			)
			(stroke
				(width 0)
				(type default)
			)
			(fill no)
			(layer "B.CrtYd")
		)
		(fp_line
			(start -0.2794 0.9906)
			(end -0.2794 -0.1016)
			(stroke
				(width 0.1)
				(type default)
			)
			(layer "B.Fab")
		)
		(fp_line
			(start 0.2794 0.9906)
			(end -0.2794 0.9906)
			(stroke
				(width 0.1)
				(type default)
			)
			(layer "B.Fab")
		)
		(fp_line
			(start -0.2794 -0.1016)
			(end 0.2794 -0.1016)
			(stroke
				(width 0.1)
				(type default)
			)
			(layer "B.Fab")
		)
		(fp_line
			(start 0.2794 -0.1016)
			(end 0.2794 0.9906)
			(stroke
				(width 0.1)
				(type default)
			)
			(layer "B.Fab")
		)
		(pad "1" smd rect
			(at 0 0 90)
			(size 0.508 0.508)
			(layers "B.Cu" "B.Mask" "B.Paste")
			(net "CLK_100M_CPU0_PE_REFCLK_DP")
		)
		(pad "2" smd rect
			(at 0 0.889 90)
			(size 0.508 0.508)
			(layers "B.Cu" "B.Mask" "B.Paste")
			(net "GND")
		)
		(zone
			(layer "B.Cu")
			(hatch none 0.5)
			(connect_pads
				(clearance 0)
			)
			(min_thickness 0.25)
			(keepout
				(tracks not_allowed)
				(vias allowed)
				(pads allowed)
				(copperpour not_allowed)
				(footprints allowed)
			)
			(placement
				(enabled no)
				(sheetname "")
			)
			(fill
				(thermal_gap 0.5)
				(thermal_bridge_width 0.5)
				(island_removal_mode 0)
			)
			(polygon
				(pts
					(xy 175.577754 -83.693) (xy 175.577754 -84.201) (xy 175.958754 -84.201) (xy 175.958754 -83.693)
				)
			)
		)
		(zone
			(layer "B.Cu")
			(hatch none 0.5)
			(connect_pads
				(clearance 0)
			)
			(min_thickness 0.25)
			(keepout
				(tracks allowed)
				(vias not_allowed)
				(pads allowed)
				(copperpour not_allowed)
				(footprints allowed)
			)
			(placement
				(enabled no)
				(sheetname "")
			)
			(fill
				(thermal_gap 0.5)
				(thermal_bridge_width 0.5)
				(island_removal_mode 0)
			)
			(polygon
				(pts
					(xy 175.958754 -83.693) (xy 175.958754 -84.201) (xy 175.577754 -84.201) (xy 175.577754 -83.693)
				)
			)
		)
	)
)
